# T6G (Grand Teton) — schematic netlist excerpt (pin names and nets, part order shuffled) for the footprints in the layout excerpt that follows; sources: Cadence DE-HDL packaged netlist, KiCad conversion of 04192023_DAF0TMB3IC0_F0TG_MB_C_brd_V02_OCP.brd

R1351  Q_RES  2.2K 5% CHIP  pkg 0402LF  page 83 : A = RST_CPU0_KBRST_R_N ; B = PVDD18_S5_P0

(kicad_pcb
	(version 20260206)
	(generator "pcbnew")
	(generator_version "10.0")
	(general
		(thickness 1.6)
		(legacy_teardrops no)
	)
	(paper "A4")
	(title_block
		(title "04192023_DAF0TMB3IC0_F0TG_MB_C_brd_V02_OCP.brd")
		(comment 1 "Grand Teton / footprints 6102-6102 of 8354")
	)
	(layers
		(0 "F.Cu" signal "TOP")
		(4 "In1.Cu" signal "GND")
		(6 "In2.Cu" signal "IN1")
		(8 "In3.Cu" signal "GND1")
		(10 "In4.Cu" signal "IN2")
		(12 "In5.Cu" signal "GND2")
		(14 "In6.Cu" signal "IN3")
		(16 "In7.Cu" signal "GND3")
		(18 "In8.Cu" signal "VCC")
		(20 "In9.Cu" signal "VCC1")
		(22 "In10.Cu" signal "GND4")
		(24 "In11.Cu" signal "IN4")
		(26 "In12.Cu" signal "GND5")
		(28 "In13.Cu" signal "IN5")
		(30 "In14.Cu" signal "GND6")
		(32 "In15.Cu" signal "IN6")
		(34 "In16.Cu" signal "GND7")
		(2 "B.Cu" signal "BOTTOM")
		(9 "F.Adhes" user "F.Adhesive")
		(11 "B.Adhes" user "B.Adhesive")
		(13 "F.Paste" user "Package Geometry/Pastemask Top")
		(15 "B.Paste" user "Package Geometry/Pastemask Bottom")
		(5 "F.SilkS" user "Ref Des/Silkscreen Top")
		(7 "B.SilkS" user "Ref Des/Silkscreen Bottom")
		(1 "F.Mask" user "Board Geometry/Soldermask Top")
		(3 "B.Mask" user "Board Geometry/Soldermask Bottom")
		(17 "Dwgs.User" user "User.Drawings")
		(19 "Cmts.User" user "User.Comments")
		(21 "Eco1.User" user "User.Eco1")
		(23 "Eco2.User" user "User.Eco2")
		(25 "Edge.Cuts" user "Board Geometry/Outline")
		(27 "Margin" user)
		(31 "F.CrtYd" user "Package Geometry/Place Bound Top")
		(29 "B.CrtYd" user "Package Geometry/Place Bound Bottom")
		(35 "F.Fab" user "Ref Des/Assembly Top")
		(33 "B.Fab" user "Ref Des/Assembly Bottom")
	)
	(footprint ""
		(layer "B.Cu")
		(at 396.546578 -327.766172 180)
		(property "Reference" "R1351"
			(at 0 0 0)
			(layer "B.SilkS")
			(hide yes)
			(effects
				(font
					(size 1.27 1.27)
				)
				(justify mirror)
			)
		)
		(property "Value" ""
			(at 0 0 0)
			(layer "B.Fab")
			(effects
				(font
					(size 1.27 1.27)
				)
				(justify mirror)
			)
		)
		(duplicate_pad_numbers_are_jumpers no)
		(fp_line
			(start 0.7874 0.4064)
			(end 0.7874 -0.4064)
			(stroke
				(width 0.1524)
				(type default)
			)
			(layer "B.SilkS")
		)
		(fp_line
			(start 0.7874 -0.4064)
			(end -0.7874 -0.4064)
			(stroke
				(width 0.1524)
				(type default)
			)
			(layer "B.SilkS")
		)
		(fp_line
			(start -0.7874 0.4064)
			(end 0.7874 0.4064)
			(stroke
				(width 0.1524)
				(type default)
			)
			(layer "B.SilkS")
		)
		(fp_line
			(start -0.7874 -0.4064)
			(end -0.7874 0.4064)
			(stroke
				(width 0.1524)
				(type default)
			)
			(layer "B.SilkS")
		)
		(fp_line
			(start 0.67945 0.3048)
			(end 0.67945 -0.305054)
			(stroke
				(width 0.1)
				(type default)
			)
			(layer "B.Fab")
		)
		(fp_line
			(start 0.67945 -0.305054)
			(end 0.12065 -0.305054)
			(stroke
				(width 0.1)
				(type default)
			)
			(layer "B.Fab")
		)
		(fp_line
			(start 0.12065 0.3048)
			(end 0.67945 0.3048)
			(stroke
				(width 0.1)
				(type default)
			)
			(layer "B.Fab")
		)
		(fp_line
			(start 0.12065 0.2794)
			(end 0.12065 0.3048)
			(stroke
				(width 0.1)
				(type default)
			)
			(layer "B.Fab")
		)
		(fp_line
			(start 0.12065 -0.2794)
			(end -0.12065 -0.2794)
			(stroke
				(width 0.1)
				(type default)
			)
			(layer "B.Fab")
		)
		(fp_line
			(start 0.12065 -0.305054)
			(end 0.12065 -0.2794)
			(stroke
				(width 0.1)
				(type default)
			)
			(layer "B.Fab")
		)
		(fp_line
			(start -0.120396 0.3048)
			(end -0.120396 0.2794)
			(stroke
				(width 0.1)
				(type default)
			)
			(layer "B.Fab")
		)
		(fp_line
			(start -0.120396 0.2794)
			(end 0.12065 0.2794)
			(stroke
				(width 0.1)
				(type default)
			)
			(layer "B.Fab")
		)
		(fp_line
			(start -0.12065 -0.2794)
			(end -0.12065 -0.3048)
			(stroke
				(width 0.1)
				(type default)
			)
			(layer "B.Fab")
		)
		(fp_line
			(start -0.12065 -0.3048)
			(end -0.67945 -0.3048)
			(stroke
				(width 0.1)
				(type default)
			)
			(layer "B.Fab")
		)
		(fp_line
			(start -0.67945 0.3048)
			(end -0.120396 0.3048)
			(stroke
				(width 0.1)
				(type default)
			)
			(layer "B.Fab")
		)
		(fp_line
			(start -0.67945 -0.3048)
			(end -0.67945 0.3048)
			(stroke
				(width 0.1)
				(type default)
			)
			(layer "B.Fab")
		)
		(pad "1" smd circle
			(at 0.40005 0)
			(size 0 0)
			(layers "B.Cu" "B.Mask" "B.Paste")
			(net "RST_CPU0_KBRST_R_N")
		)
		(pad "2" smd circle
			(at -0.40005 0)
			(size 0 0)
			(layers "B.Cu" "B.Mask" "B.Paste")
			(net "PVDD18_S5_P0")
		)
	)
)
